FILE_TYPE=LIBRARY_PARTS;
primitive 'SC22P50V2JN-4GP_SMD-BCG';
  pin
    '1':
      PIN_NUMBER='(1)';
      PIN_TYPE='ANALOG';
      NO_LOAD_CHECK='Both';
      NO_IO_CHECK='Both';
      NO_ASSERT_CHECK='TRUE';
      NO_DIR_CHECK='TRUE';
      ALLOW_CONNECT='TRUE';
    '2':
      PIN_NUMBER='(2)';
      PIN_TYPE='ANALOG';
      NO_LOAD_CHECK='Both';
      NO_IO_CHECK='Both';
      NO_ASSERT_CHECK='TRUE';
      NO_DIR_CHECK='TRUE';
      ALLOW_CONNECT='TRUE';
  end_pin;
  body
    PART_NAME='SC22P50V2JN-4GP';
    BODY_NAME='SC22P50V2JN-4GP';
    PHYS_DES_PREFIX='C';
    CLASS='DISCRETE';
  end_body;
end_primitive;

END.
